(kicad_pcb
	(version 20260206)
	(generator "pcbnew")
	(generator_version "10.0")
	(general
		(thickness 1.6)
		(legacy_teardrops no)
	)
	(paper "A4")
	(title_block
		(title "01162023_DA0F0TEBIF0_F0T_Expander_BD_F_brd_V02_OCP.brd")
		(comment 1 "Grand Teton / footprints 5058-5064 of 9728")
	)
	(layers
		(0 "F.Cu" signal "TOP")
		(4 "In1.Cu" signal "GND")
		(6 "In2.Cu" signal "VCC")
		(8 "In3.Cu" signal "VCC1")
		(10 "In4.Cu" signal "GND1")
		(12 "In5.Cu" signal "IN1")
		(14 "In6.Cu" signal "GND2")
		(16 "In7.Cu" signal "IN2")
		(18 "In8.Cu" signal "GND3")
		(20 "In9.Cu" signal "IN3")
		(22 "In10.Cu" signal "GND4")
		(24 "In11.Cu" signal "IN4")
		(26 "In12.Cu" signal "GND5")
		(28 "In13.Cu" signal "IN5")
		(30 "In14.Cu" signal "GND6")
		(32 "In15.Cu" signal "IN6")
		(34 "In16.Cu" signal "GND7")
		(2 "B.Cu" signal "BOTTOM")
		(9 "F.Adhes" user "F.Adhesive")
		(11 "B.Adhes" user "B.Adhesive")
		(13 "F.Paste" user "Package Geometry/Pastemask Top")
		(15 "B.Paste" user "Package Geometry/Pastemask Bottom")
		(5 "F.SilkS" user "Ref Des/Silkscreen Top")
		(7 "B.SilkS" user "Ref Des/Silkscreen Bottom")
		(1 "F.Mask" user "Board Geometry/Soldermask Top")
		(3 "B.Mask" user "Board Geometry/Soldermask Bottom")
		(17 "Dwgs.User" user "User.Drawings")
		(19 "Cmts.User" user "User.Comments")
		(21 "Eco1.User" user "User.Eco1")
		(23 "Eco2.User" user "User.Eco2")
		(25 "Edge.Cuts" user "Board Geometry/Outline")
		(27 "Margin" user)
		(31 "F.CrtYd" user "Package Geometry/Place Bound Top")
		(29 "B.CrtYd" user "Package Geometry/Place Bound Bottom")
		(35 "F.Fab" user "Ref Des/Assembly Top")
		(33 "B.Fab" user "Ref Des/Assembly Bottom")
	)
	(footprint ""
		(layer "F.Cu")
		(at 277.996142 -47.20082 90)
		(property "Reference" "C325"
			(at 0 0 90)
			(layer "F.SilkS")
			(hide yes)
			(effects
				(font
					(size 1.27 1.27)
				)
			)
		)
		(property "Value" ""
			(at 0 0 90)
			(layer "F.Fab")
			(effects
				(font
					(size 1.27 1.27)
				)
			)
		)
		(duplicate_pad_numbers_are_jumpers no)
		(fp_line
			(start 0.7874 -0.4064)
			(end 0.7874 0.4064)
			(stroke
				(width 0.1524)
				(type default)
			)
			(layer "F.SilkS")
		)
		(fp_line
			(start -0.7874 -0.4064)
			(end 0.7874 -0.4064)
			(stroke
				(width 0.1524)
				(type default)
			)
			(layer "F.SilkS")
		)
		(fp_line
			(start 0.7874 0.4064)
			(end -0.7874 0.4064)
			(stroke
				(width 0.1524)
				(type default)
			)
			(layer "F.SilkS")
		)
		(fp_line
			(start -0.7874 0.4064)
			(end -0.7874 -0.4064)
			(stroke
				(width 0.1524)
				(type default)
			)
			(layer "F.SilkS")
		)
		(fp_line
			(start -0.12065 -0.305054)
			(end -0.12065 -0.2794)
			(stroke
				(width 0.1)
				(type default)
			)
			(layer "F.Fab")
		)
		(fp_line
			(start -0.67945 -0.305054)
			(end -0.12065 -0.305054)
			(stroke
				(width 0.1)
				(type default)
			)
			(layer "F.Fab")
		)
		(fp_line
			(start 0.67945 -0.3048)
			(end 0.67945 0.3048)
			(stroke
				(width 0.1)
				(type default)
			)
			(layer "F.Fab")
		)
		(fp_line
			(start 0.12065 -0.3048)
			(end 0.67945 -0.3048)
			(stroke
				(width 0.1)
				(type default)
			)
			(layer "F.Fab")
		)
		(fp_line
			(start 0.12065 -0.2794)
			(end 0.12065 -0.3048)
			(stroke
				(width 0.1)
				(type default)
			)
			(layer "F.Fab")
		)
		(fp_line
			(start -0.12065 -0.2794)
			(end 0.12065 -0.2794)
			(stroke
				(width 0.1)
				(type default)
			)
			(layer "F.Fab")
		)
		(fp_line
			(start 0.120396 0.2794)
			(end -0.12065 0.2794)
			(stroke
				(width 0.1)
				(type default)
			)
			(layer "F.Fab")
		)
		(fp_line
			(start -0.12065 0.2794)
			(end -0.12065 0.3048)
			(stroke
				(width 0.1)
				(type default)
			)
			(layer "F.Fab")
		)
		(fp_line
			(start 0.67945 0.3048)
			(end 0.120396 0.3048)
			(stroke
				(width 0.1)
				(type default)
			)
			(layer "F.Fab")
		)
		(fp_line
			(start 0.120396 0.3048)
			(end 0.120396 0.2794)
			(stroke
				(width 0.1)
				(type default)
			)
			(layer "F.Fab")
		)
		(fp_line
			(start -0.12065 0.3048)
			(end -0.67945 0.3048)
			(stroke
				(width 0.1)
				(type default)
			)
			(layer "F.Fab")
		)
		(fp_line
			(start -0.67945 0.3048)
			(end -0.67945 -0.305054)
			(stroke
				(width 0.1)
				(type default)
			)
			(layer "F.Fab")
		)
		(pad "1" smd circle
			(at -0.40005 0 90)
			(size 0 0)
			(layers "F.Cu" "F.Mask" "F.Paste")
			(net "P12V_SSD9_R")
		)
		(pad "2" smd circle
			(at 0.40005 0 90)
			(size 0 0)
			(layers "F.Cu" "F.Mask" "F.Paste")
			(net "GND")
		)
	)
	(footprint ""
		(layer "F.Cu")
		(at 210.419442 -244.016276 -90)
		(property "Reference" "C2707"
			(at 0 0 270)
			(layer "F.SilkS")
			(hide yes)
			(effects
				(font
					(size 1.27 1.27)
				)
			)
		)
		(property "Value" ""
			(at 0 0 270)
			(layer "F.Fab")
			(effects
				(font
					(size 1.27 1.27)
				)
			)
		)
		(duplicate_pad_numbers_are_jumpers no)
		(fp_line
			(start -0.7874 0.4064)
			(end -0.7874 -0.4064)
			(stroke
				(width 0.1524)
				(type default)
			)
			(layer "F.SilkS")
		)
		(fp_line
			(start 0.7874 0.4064)
			(end -0.7874 0.4064)
			(stroke
				(width 0.1524)
				(type default)
			)
			(layer "F.SilkS")
		)
		(fp_line
			(start -0.7874 -0.4064)
			(end 0.7874 -0.4064)
			(stroke
				(width 0.1524)
				(type default)
			)
			(layer "F.SilkS")
		)
		(fp_line
			(start 0.7874 -0.4064)
			(end 0.7874 0.4064)
			(stroke
				(width 0.1524)
				(type default)
			)
			(layer "F.SilkS")
		)
		(fp_line
			(start -0.67945 0.3048)
			(end -0.67945 -0.305054)
			(stroke
				(width 0.1)
				(type default)
			)
			(layer "F.Fab")
		)
		(fp_line
			(start -0.12065 0.3048)
			(end -0.67945 0.3048)
			(stroke
				(width 0.1)
				(type default)
			)
			(layer "F.Fab")
		)
		(fp_line
			(start 0.120396 0.3048)
			(end 0.120396 0.2794)
			(stroke
				(width 0.1)
				(type default)
			)
			(layer "F.Fab")
		)
		(fp_line
			(start 0.67945 0.3048)
			(end 0.120396 0.3048)
			(stroke
				(width 0.1)
				(type default)
			)
			(layer "F.Fab")
		)
		(fp_line
			(start -0.12065 0.2794)
			(end -0.12065 0.3048)
			(stroke
				(width 0.1)
				(type default)
			)
			(layer "F.Fab")
		)
		(fp_line
			(start 0.120396 0.2794)
			(end -0.12065 0.2794)
			(stroke
				(width 0.1)
				(type default)
			)
			(layer "F.Fab")
		)
		(fp_line
			(start -0.12065 -0.2794)
			(end 0.12065 -0.2794)
			(stroke
				(width 0.1)
				(type default)
			)
			(layer "F.Fab")
		)
		(fp_line
			(start 0.12065 -0.2794)
			(end 0.12065 -0.3048)
			(stroke
				(width 0.1)
				(type default)
			)
			(layer "F.Fab")
		)
		(fp_line
			(start 0.12065 -0.3048)
			(end 0.67945 -0.3048)
			(stroke
				(width 0.1)
				(type default)
			)
			(layer "F.Fab")
		)
		(fp_line
			(start 0.67945 -0.3048)
			(end 0.67945 0.3048)
			(stroke
				(width 0.1)
				(type default)
			)
			(layer "F.Fab")
		)
		(fp_line
			(start -0.67945 -0.305054)
			(end -0.12065 -0.305054)
			(stroke
				(width 0.1)
				(type default)
			)
			(layer "F.Fab")
		)
		(fp_line
			(start -0.12065 -0.305054)
			(end -0.12065 -0.2794)
			(stroke
				(width 0.1)
				(type default)
			)
			(layer "F.Fab")
		)
		(pad "1" smd circle
			(at -0.40005 0 270)
			(size 0 0)
			(layers "F.Cu" "F.Mask" "F.Paste")
			(net "GND")
		)
		(pad "2" smd circle
			(at 0.40005 0 270)
			(size 0 0)
			(layers "F.Cu" "F.Mask" "F.Paste")
			(net "P3V3_AUX")
		)
	)
	(footprint ""
		(layer "F.Cu")
		(at 438.328308 -300.64202 -90)
		(property "Reference" "R3989"
			(at 0 0 270)
			(layer "F.SilkS")
			(hide yes)
			(effects
				(font
					(size 1.27 1.27)
				)
			)
		)
		(property "Value" ""
			(at 0 0 270)
			(layer "F.Fab")
			(effects
				(font
					(size 1.27 1.27)
				)
			)
		)
		(duplicate_pad_numbers_are_jumpers no)
		(fp_line
			(start -0.7874 0.4064)
			(end -0.7874 -0.4064)
			(stroke
				(width 0.1524)
				(type default)
			)
			(layer "F.SilkS")
		)
		(fp_line
			(start 0.7874 0.4064)
			(end -0.7874 0.4064)
			(stroke
				(width 0.1524)
				(type default)
			)
			(layer "F.SilkS")
		)
		(fp_line
			(start -0.7874 -0.4064)
			(end 0.7874 -0.4064)
			(stroke
				(width 0.1524)
				(type default)
			)
			(layer "F.SilkS")
		)
		(fp_line
			(start 0.7874 -0.4064)
			(end 0.7874 0.4064)
			(stroke
				(width 0.1524)
				(type default)
			)
			(layer "F.SilkS")
		)
		(fp_line
			(start -0.67945 0.3048)
			(end -0.67945 -0.305054)
			(stroke
				(width 0.1)
				(type default)
			)
			(layer "F.Fab")
		)
		(fp_line
			(start -0.12065 0.3048)
			(end -0.67945 0.3048)
			(stroke
				(width 0.1)
				(type default)
			)
			(layer "F.Fab")
		)
		(fp_line
			(start 0.120396 0.3048)
			(end 0.120396 0.2794)
			(stroke
				(width 0.1)
				(type default)
			)
			(layer "F.Fab")
		)
		(fp_line
			(start 0.67945 0.3048)
			(end 0.120396 0.3048)
			(stroke
				(width 0.1)
				(type default)
			)
			(layer "F.Fab")
		)
		(fp_line
			(start -0.12065 0.2794)
			(end -0.12065 0.3048)
			(stroke
				(width 0.1)
				(type default)
			)
			(layer "F.Fab")
		)
		(fp_line
			(start 0.120396 0.2794)
			(end -0.12065 0.2794)
			(stroke
				(width 0.1)
				(type default)
			)
			(layer "F.Fab")
		)
		(fp_line
			(start -0.12065 -0.2794)
			(end 0.12065 -0.2794)
			(stroke
				(width 0.1)
				(type default)
			)
			(layer "F.Fab")
		)
		(fp_line
			(start 0.12065 -0.2794)
			(end 0.12065 -0.3048)
			(stroke
				(width 0.1)
				(type default)
			)
			(layer "F.Fab")
		)
		(fp_line
			(start 0.12065 -0.3048)
			(end 0.67945 -0.3048)
			(stroke
				(width 0.1)
				(type default)
			)
			(layer "F.Fab")
		)
		(fp_line
			(start 0.67945 -0.3048)
			(end 0.67945 0.3048)
			(stroke
				(width 0.1)
				(type default)
			)
			(layer "F.Fab")
		)
		(fp_line
			(start -0.67945 -0.305054)
			(end -0.12065 -0.305054)
			(stroke
				(width 0.1)
				(type default)
			)
			(layer "F.Fab")
		)
		(fp_line
			(start -0.12065 -0.305054)
			(end -0.12065 -0.2794)
			(stroke
				(width 0.1)
				(type default)
			)
			(layer "F.Fab")
		)
		(pad "1" smd circle
			(at -0.40005 0 270)
			(size 0 0)
			(layers "F.Cu" "F.Mask" "F.Paste")
			(net "I2C0_PEX3_SDA")
		)
		(pad "2" smd circle
			(at 0.40005 0 270)
			(size 0 0)
			(layers "F.Cu" "F.Mask" "F.Paste")
			(net "I2C_PEX3_HOST_SDA")
		)
	)
	(footprint ""
		(layer "F.Cu")
		(at 99.36353 -220.544644 180)
		(property "Reference" "C838"
			(at 0 0 180)
			(layer "F.SilkS")
			(hide yes)
			(effects
				(font
					(size 1.27 1.27)
				)
			)
		)
		(property "Value" ""
			(at 0 0 180)
			(layer "F.Fab")
			(effects
				(font
					(size 1.27 1.27)
				)
			)
		)
		(duplicate_pad_numbers_are_jumpers no)
		(fp_line
			(start 0.7874 0.4064)
			(end -0.7874 0.4064)
			(stroke
				(width 0.1524)
				(type default)
			)
			(layer "F.SilkS")
		)
		(fp_line
			(start 0.7874 -0.4064)
			(end 0.7874 0.4064)
			(stroke
				(width 0.1524)
				(type default)
			)
			(layer "F.SilkS")
		)
		(fp_line
			(start -0.7874 0.4064)
			(end -0.7874 -0.4064)
			(stroke
				(width 0.1524)
				(type default)
			)
			(layer "F.SilkS")
		)
		(fp_line
			(start -0.7874 -0.4064)
			(end 0.7874 -0.4064)
			(stroke
				(width 0.1524)
				(type default)
			)
			(layer "F.SilkS")
		)
		(fp_line
			(start 0.67945 0.3048)
			(end 0.120396 0.3048)
			(stroke
				(width 0.1)
				(type default)
			)
			(layer "F.Fab")
		)
		(fp_line
			(start 0.67945 -0.3048)
			(end 0.67945 0.3048)
			(stroke
				(width 0.1)
				(type default)
			)
			(layer "F.Fab")
		)
		(fp_line
			(start 0.12065 -0.2794)
			(end 0.12065 -0.3048)
			(stroke
				(width 0.1)
				(type default)
			)
			(layer "F.Fab")
		)
		(fp_line
			(start 0.12065 -0.3048)
			(end 0.67945 -0.3048)
			(stroke
				(width 0.1)
				(type default)
			)
			(layer "F.Fab")
		)
		(fp_line
			(start 0.120396 0.3048)
			(end 0.120396 0.2794)
			(stroke
				(width 0.1)
				(type default)
			)
			(layer "F.Fab")
		)
		(fp_line
			(start 0.120396 0.2794)
			(end -0.12065 0.2794)
			(stroke
				(width 0.1)
				(type default)
			)
			(layer "F.Fab")
		)
		(fp_line
			(start -0.12065 0.3048)
			(end -0.67945 0.3048)
			(stroke
				(width 0.1)
				(type default)
			)
			(layer "F.Fab")
		)
		(fp_line
			(start -0.12065 0.2794)
			(end -0.12065 0.3048)
			(stroke
				(width 0.1)
				(type default)
			)
			(layer "F.Fab")
		)
		(fp_line
			(start -0.12065 -0.2794)
			(end 0.12065 -0.2794)
			(stroke
				(width 0.1)
				(type default)
			)
			(layer "F.Fab")
		)
		(fp_line
			(start -0.12065 -0.305054)
			(end -0.12065 -0.2794)
			(stroke
				(width 0.1)
				(type default)
			)
			(layer "F.Fab")
		)
		(fp_line
			(start -0.67945 0.3048)
			(end -0.67945 -0.305054)
			(stroke
				(width 0.1)
				(type default)
			)
			(layer "F.Fab")
		)
		(fp_line
			(start -0.67945 -0.305054)
			(end -0.12065 -0.305054)
			(stroke
				(width 0.1)
				(type default)
			)
			(layer "F.Fab")
		)
		(pad "1" smd circle
			(at -0.40005 0 180)
			(size 0 0)
			(layers "F.Cu" "F.Mask" "F.Paste")
			(net "PWR_EN_PEX_R")
		)
		(pad "2" smd circle
			(at 0.40005 0 180)
			(size 0 0)
			(layers "F.Cu" "F.Mask" "F.Paste")
			(net "GND")
		)
	)
	(footprint ""
		(layer "F.Cu")
		(at 234.965494 -180.68163 -90)
		(property "Reference" "R5494"
			(at 0 0 270)
			(layer "F.SilkS")
			(hide yes)
			(effects
				(font
					(size 1.27 1.27)
				)
			)
		)
		(property "Value" ""
			(at 0 0 270)
			(layer "F.Fab")
			(effects
				(font
					(size 1.27 1.27)
				)
			)
		)
		(duplicate_pad_numbers_are_jumpers no)
		(fp_line
			(start -0.7874 0.4064)
			(end -0.7874 -0.4064)
			(stroke
				(width 0.1524)
				(type default)
			)
			(layer "F.SilkS")
		)
		(fp_line
			(start 0.7874 0.4064)
			(end -0.7874 0.4064)
			(stroke
				(width 0.1524)
				(type default)
			)
			(layer "F.SilkS")
		)
		(fp_line
			(start -0.7874 -0.4064)
			(end 0.7874 -0.4064)
			(stroke
				(width 0.1524)
				(type default)
			)
			(layer "F.SilkS")
		)
		(fp_line
			(start 0.7874 -0.4064)
			(end 0.7874 0.4064)
			(stroke
				(width 0.1524)
				(type default)
			)
			(layer "F.SilkS")
		)
		(fp_line
			(start -0.67945 0.3048)
			(end -0.67945 -0.305054)
			(stroke
				(width 0.1)
				(type default)
			)
			(layer "F.Fab")
		)
		(fp_line
			(start -0.12065 0.3048)
			(end -0.67945 0.3048)
			(stroke
				(width 0.1)
				(type default)
			)
			(layer "F.Fab")
		)
		(fp_line
			(start 0.120396 0.3048)
			(end 0.120396 0.2794)
			(stroke
				(width 0.1)
				(type default)
			)
			(layer "F.Fab")
		)
		(fp_line
			(start 0.67945 0.3048)
			(end 0.120396 0.3048)
			(stroke
				(width 0.1)
				(type default)
			)
			(layer "F.Fab")
		)
		(fp_line
			(start -0.12065 0.2794)
			(end -0.12065 0.3048)
			(stroke
				(width 0.1)
				(type default)
			)
			(layer "F.Fab")
		)
		(fp_line
			(start 0.120396 0.2794)
			(end -0.12065 0.2794)
			(stroke
				(width 0.1)
				(type default)
			)
			(layer "F.Fab")
		)
		(fp_line
			(start -0.12065 -0.2794)
			(end 0.12065 -0.2794)
			(stroke
				(width 0.1)
				(type default)
			)
			(layer "F.Fab")
		)
		(fp_line
			(start 0.12065 -0.2794)
			(end 0.12065 -0.3048)
			(stroke
				(width 0.1)
				(type default)
			)
			(layer "F.Fab")
		)
		(fp_line
			(start 0.12065 -0.3048)
			(end 0.67945 -0.3048)
			(stroke
				(width 0.1)
				(type default)
			)
			(layer "F.Fab")
		)
		(fp_line
			(start 0.67945 -0.3048)
			(end 0.67945 0.3048)
			(stroke
				(width 0.1)
				(type default)
			)
			(layer "F.Fab")
		)
		(fp_line
			(start -0.67945 -0.305054)
			(end -0.12065 -0.305054)
			(stroke
				(width 0.1)
				(type default)
			)
			(layer "F.Fab")
		)
		(fp_line
			(start -0.12065 -0.305054)
			(end -0.12065 -0.2794)
			(stroke
				(width 0.1)
				(type default)
			)
			(layer "F.Fab")
		)
		(pad "1" smd circle
			(at -0.40005 0 270)
			(size 0 0)
			(layers "F.Cu" "F.Mask" "F.Paste")
			(net "RST_BIC_EXTRST_N")
		)
		(pad "2" smd circle
			(at 0.40005 0 270)
			(size 0 0)
			(layers "F.Cu" "F.Mask" "F.Paste")
			(net "RST_BIC_EXTRST_R_N")
		)
	)
	(footprint ""
		(layer "F.Cu")
		(at 265.971782 -24.807418)
		(property "Reference" "R438"
			(at 0 0 0)
			(layer "F.SilkS")
			(hide yes)
			(effects
				(font
					(size 1.27 1.27)
				)
			)
		)
		(property "Value" ""
			(at 0 0 0)
			(layer "F.Fab")
			(effects
				(font
					(size 1.27 1.27)
				)
			)
		)
		(duplicate_pad_numbers_are_jumpers no)
		(fp_line
			(start -0.7874 -0.4064)
			(end 0.7874 -0.4064)
			(stroke
				(width 0.1524)
				(type default)
			)
			(layer "F.SilkS")
		)
		(fp_line
			(start -0.7874 0.4064)
			(end -0.7874 -0.4064)
			(stroke
				(width 0.1524)
				(type default)
			)
			(layer "F.SilkS")
		)
		(fp_line
			(start 0.7874 -0.4064)
			(end 0.7874 0.4064)
			(stroke
				(width 0.1524)
				(type default)
			)
			(layer "F.SilkS")
		)
		(fp_line
			(start 0.7874 0.4064)
			(end -0.7874 0.4064)
			(stroke
				(width 0.1524)
				(type default)
			)
			(layer "F.SilkS")
		)
		(fp_line
			(start -0.67945 -0.305054)
			(end -0.12065 -0.305054)
			(stroke
				(width 0.1)
				(type default)
			)
			(layer "F.Fab")
		)
		(fp_line
			(start -0.67945 0.3048)
			(end -0.67945 -0.305054)
			(stroke
				(width 0.1)
				(type default)
			)
			(layer "F.Fab")
		)
		(fp_line
			(start -0.12065 -0.305054)
			(end -0.12065 -0.2794)
			(stroke
				(width 0.1)
				(type default)
			)
			(layer "F.Fab")
		)
		(fp_line
			(start -0.12065 -0.2794)
			(end 0.12065 -0.2794)
			(stroke
				(width 0.1)
				(type default)
			)
			(layer "F.Fab")
		)
		(fp_line
			(start -0.12065 0.2794)
			(end -0.12065 0.3048)
			(stroke
				(width 0.1)
				(type default)
			)
			(layer "F.Fab")
		)
		(fp_line
			(start -0.12065 0.3048)
			(end -0.67945 0.3048)
			(stroke
				(width 0.1)
				(type default)
			)
			(layer "F.Fab")
		)
		(fp_line
			(start 0.120396 0.2794)
			(end -0.12065 0.2794)
			(stroke
				(width 0.1)
				(type default)
			)
			(layer "F.Fab")
		)
		(fp_line
			(start 0.120396 0.3048)
			(end 0.120396 0.2794)
			(stroke
				(width 0.1)
				(type default)
			)
			(layer "F.Fab")
		)
		(fp_line
			(start 0.12065 -0.3048)
			(end 0.67945 -0.3048)
			(stroke
				(width 0.1)
				(type default)
			)
			(layer "F.Fab")
		)
		(fp_line
			(start 0.12065 -0.2794)
			(end 0.12065 -0.3048)
			(stroke
				(width 0.1)
				(type default)
			)
			(layer "F.Fab")
		)
		(fp_line
			(start 0.67945 -0.3048)
			(end 0.67945 0.3048)
			(stroke
				(width 0.1)
				(type default)
			)
			(layer "F.Fab")
		)
		(fp_line
			(start 0.67945 0.3048)
			(end 0.120396 0.3048)
			(stroke
				(width 0.1)
				(type default)
			)
			(layer "F.Fab")
		)
		(pad "1" smd circle
			(at -0.40005 0)
			(size 0 0)
			(layers "F.Cu" "F.Mask" "F.Paste")
			(net "P3V3_SSD9")
		)
		(pad "2" smd circle
			(at 0.40005 0)
			(size 0 0)
			(layers "F.Cu" "F.Mask" "F.Paste")
			(net "PU_CLKREQ9")
		)
	)
	(footprint ""
		(layer "F.Cu")
		(at 64.455802 -343.952322 90)
		(property "Reference" "C125"
			(at 0 0 90)
			(layer "F.SilkS")
			(hide yes)
			(effects
				(font
					(size 1.27 1.27)
				)
			)
		)
		(property "Value" ""
			(at 0 0 90)
			(layer "F.Fab")
			(effects
				(font
					(size 1.27 1.27)
				)
			)
		)
		(duplicate_pad_numbers_are_jumpers no)
		(fp_line
			(start 0.299974 -0.150114)
			(end 0.299974 0.150114)
			(stroke
				(width 0.1)
				(type default)
			)
			(layer "F.Fab")
		)
		(fp_line
			(start -0.299974 -0.150114)
			(end 0.299974 -0.150114)
			(stroke
				(width 0.1)
				(type default)
			)
			(layer "F.Fab")
		)
		(fp_line
			(start 0.299974 0.150114)
			(end -0.299974 0.150114)
			(stroke
				(width 0.1)
				(type default)
			)
			(layer "F.Fab")
		)
		(fp_line
			(start -0.299974 0.150114)
			(end -0.299974 -0.150114)
			(stroke
				(width 0.1)
				(type default)
			)
			(layer "F.Fab")
		)
		(pad "1" smd rect
			(at -0.2667 0 90)
			(size 0.3048 0.381)
			(layers "F.Cu" "F.Mask" "F.Paste")
			(net "P5E_PEX0_STN5_TX_DP<81>")
		)
		(pad "2" smd rect
			(at 0.2667 0 90)
			(size 0.3048 0.381)
			(layers "F.Cu" "F.Mask" "F.Paste")
			(net "P5E_PEX0_STN5_TX_C_DP<81>")
		)
	)
)
